FILE_TYPE = CONNECTIVITY;
{Allegro Design Entry HDL 17.4-2019 S026 (4007227) 1/17/2022}
"PAGE_NUMBER" = 392;
0"NC";
1"GND\g";
2"GND\g";
3"P1V8_CPU1_RT_1D\g";
4"GND\g";
5"GND\g";
6"GND\g";
7"P1V8_CPU1_RT_1D\g";
8"GND\g";
9"GND\g";
10"GND\g";
11"P1V8_CPU1_RT_1D\g";
12"GND\g";
13"GND\g";
14"GND\g";
15"P1V8_CPU1_RT_1D\g";
16"SMB_RT_CPU1_P1_ROM_MUX_1D_SCL";
17"SMB_RT_CPU1_P1_ROM_MUX_1D_R_SCL";
18"SMB_RT_CPU1_P1_ROM_MUX_1D_SDA";
19"SMB_RT_CPU1_P1_ROM_MUX_1D_R_SDA";
20"RT_CPU1_P1_SCAN_MODE";
21"JTAG_TDI_RT_CPU1_P1";
22"JTAG_TMS_RT_CPU1_P1";
23"JTAG_TDO_RT_CPU1_P1";
24"JTAG_TCK_RT_CPU1_P1";
25"P1V8_CPU1_RT_1D\g";
26"JTAG_TMS_RT_CPU1_P1";
27"RST_RT_CPU1_P1_RESET_R_N";
28"RT_CPU1_P1_ADDR3";
29"RT_CPU1_P1_ADDR2";
30"RT_CPU1_P1_ADDR1";
31"RT_CPU1_P1_ADDR3";
32"TEST2_RT_CPU1_P1";
33"TEST1_RT_CPU1_P1";
34"TEST0_RT_CPU1_P1";
35"SMB_RT_CPU1_P1_R2_SDA";
36"RST_RT_CPU1_P1_PERST_R_N";
37"MODE_RT_CPU1_P1";
38"JTAG_TEST_MODE_RT_CPU1_P1";
39"TEST2_RT_CPU1_P1";
40"GPIO2_RT_CPU1_P1";
41"GPIO3_RT_CPU1_P1";
42"TEST0_RT_CPU1_P1";
43"GPIO3_RT_CPU1_P1";
44"TEST1_RT_CPU1_P1";
45"CLK_100M_RETIMER_CPU1_P1_DN";
46"CLK_100M_RETIMER_CPU1_P1_R_DN";
47"CLK_100M_RETIMER_CPU1_P1_R_DP";
48"CLK_100M_RETIMER_CPU1_P1_DP";
49"RT_CPU1_P1_ADDR2";
50"RT_CPU1_P1_ADDR1";
51"SMB_RT_CPU1_P1_R_SDA";
52"SMB_RT_CPU1_P1_R_SCL";
53"GPIO2_RT_CPU1_P1";
54"RXDET_BYP_RT_CPU1_P1";
55"SMB_RT_CPU1_P1_R2_SCL";
56"GND\g";
57"P1V8_CPU1_RT_1D\g";
58"P1V8_CPU1_RT_1D\g";
59"GND\g";
60"RST_RT_CPU1_P1_PERST_R_N";
61"JTAG_TCK_RT_CPU1_P1";
62"JTAG_TDO_RT_CPU1_P1";
63"RST_RT_CPU1_P1_RESET_N";
64"JTAG_TDI_RT_CPU1_P1";
65"JTAG_TRST_RT_CPU1_P1_N";
66"JTAG_TEST_MODE_RT_CPU1_P1";
67"MODE_RT_CPU1_P1";
68"RXDET_BYP_RT_CPU1_P1";
69"RT_CPU1_P1_SCAN_MODE";
70"RST_RT_CPU1_P1_RESET_R_N";
71"RST_RT_CPU1_P1_PERST_N";
72"CLKREQ_RT_CPU1_P1_N";
%"UNIVERSAL_GND"
"1","(-3475,4750)","0","pure_quanta_power","I100";
;
CDS_LIB"pure_quanta_power"
HDL_POWER"GND";
"A"56;
%"Q_RES"
"2","(-3475,5175)","0","pure_quanta","I101";
;
LOCATION"R741"
$SEC"1"
CDS_SEC"1"
TOLERANCE"1%"
VALUE"1K"
WATTAGE"1/20W"
MATERIAL"EMPTY"
PACK_TYPE"0201LF"
CDS_LIB"pure_quanta"
PART_NUMBER"CS21001FE07";
"A"
$PN"1"28;
"B"
$PN"2"56;
%"Q_RES"
"2","(-3175,5175)","0","pure_quanta","I102";
;
LOCATION"R746"
$SEC"1"
CDS_SEC"1"
TOLERANCE"1%"
VALUE"20K"
PACK_TYPE"0201LF"
MATERIAL"CHIP"
WATTAGE"1/20W"
CDS_LIB"pure_quanta"
PART_NUMBER"CS32001FE00";
"A"
$PN"1"29;
"B"
$PN"2"56;
%"Q_RES"
"2","(-3475,5950)","0","pure_quanta","I103";
;
LOCATION"R735"
$SEC"1"
CDS_SEC"1"
PACK_TYPE"0201LF"
MATERIAL"CHIP"
VALUE"1K"
TOLERANCE"1%"
WATTAGE"1/20W"
CDS_LIB"pure_quanta"
PART_NUMBER"CS21001FE07";
"A"
$PN"1"57;
"B"
$PN"2"28;
%"Q_RES"
"2","(-3175,5950)","0","pure_quanta","I104";
;
LOCATION"R745"
$SEC"1"
CDS_SEC"1"
TOLERANCE"1%"
VALUE"1K"
WATTAGE"1/20W"
PACK_TYPE"0201LF"
MATERIAL"EMPTY"
CDS_LIB"pure_quanta"
PART_NUMBER"CS21001FE07";
"A"
$PN"1"57;
"B"
$PN"2"29;
%"Q_RES"
"2","(-2825,5175)","0","pure_quanta","I105";
;
LOCATION"R796"
$SEC"1"
CDS_SEC"1"
PACK_TYPE"0201LF"
WATTAGE"1/20W"
MATERIAL"CHIP"
VALUE"1K"
TOLERANCE"1%"
CDS_LIB"pure_quanta"
PART_NUMBER"CS21001FE07";
"A"
$PN"1"30;
"B"
$PN"2"56;
%"P1V0"
"1","(-3475,6375)","0","pure_quanta_power","I106";
;
HDL_POWER"P1V8_CPU1_RT_1D"
CDS_LIB"pure_quanta_power";
"A"57;
%"Q_RES"
"2","(-2825,5925)","0","pure_quanta","I110";
;
LOCATION"R795"
$SEC"1"
CDS_SEC"1"
MATERIAL"EMPTY"
TOLERANCE"1%"
VALUE"1K"
WATTAGE"1/20W"
PACK_TYPE"0201LF"
CDS_LIB"pure_quanta"
PART_NUMBER"CS21001FE07";
"A"
$PN"1"57;
"B"
$PN"2"30;
%"Q_RES"
"1","(-2525,2150)","0","pure_quanta","I111";
;
LOCATION"R1376"
$SEC"1"
CDS_SEC"1"
VALUE"4.7K"
PACK_TYPE"0201LF"
MATERIAL"CHIP"
CDS_LIB"pure_quanta"
TOLERANCE"5%"
WATTAGE"1/20W"
PART_NUMBER"CS24701JE04";
"B"
$PN"2"1;
"A"
$PN"1"72;
%"Q_RES"
"1","(-2550,3100)","0","pure_quanta","I115";
;
LOCATION"R1372"
$SEC"1"
CDS_SEC"1"
PACK_TYPE"0201LF"
VALUE"1K"
MATERIAL"CHIP"
CDS_LIB"pure_quanta"
WATTAGE"1/20W"
TOLERANCE"1%"
PART_NUMBER"CS21001FE07";
"B"
$PN"2"4;
"A"
$PN"1"65;
%"UNIVERSAL_GND"
"1","(-1800,2150)","1","pure_quanta_power","I121";
;
CDS_LIB"pure_quanta_power"
HDL_POWER"GND";
"A"1;
%"Q_RES"
"2","(-1450,3700)","0","pure_quanta","I125";
;
LOCATION"R1377"
$SEC"1"
CDS_SEC"1"
PACK_TYPE"0201LF"
TOLERANCE"1%"
WATTAGE"1/20W"
MATERIAL"EMPTY"
VALUE"1K"
CDS_LIB"pure_quanta"
PART_NUMBER"CS21001FE07";
"A"
$PN"1"3;
"B"
$PN"2"54;
%"Q_RES"
"2","(-1450,3175)","0","pure_quanta","I126";
;
LOCATION"R1378"
$SEC"1"
CDS_SEC"1"
PACK_TYPE"0201LF"
WATTAGE"1/20W"
VALUE"10K"
TOLERANCE"1%"
MATERIAL"CHIP"
CDS_LIB"pure_quanta"
PART_NUMBER"CS31001FE17";
"A"
$PN"1"54;
"B"
$PN"2"2;
%"GND"
"1","(-1450,2775)","0","pure_quanta_power","I127";
;
BOM_COST"MEM"
SIZE"1B"
CDS_LIB"pure_quanta_power"
HDL_POWER"GND";
"A<SIZE-1..0>\NAC"2;
%"P1V0"
"1","(-1450,4100)","0","pure_quanta_power","I129";
;
HDL_POWER"P1V8_CPU1_RT_1D"
CDS_LIB"pure_quanta_power";
"A"3;
%"UNIVERSAL_GND"
"1","(-1800,3100)","1","pure_quanta_power","I130";
;
CDS_LIB"pure_quanta_power"
HDL_POWER"GND";
"A"4;
%"Q_RES"
"2","(-8825,3300)","0","pure_quanta","I132";
;
LOCATION"R756"
$SEC"1"
CDS_SEC"1"
PACK_TYPE"0201LF"
TOLERANCE"1%"
VALUE"200"
MATERIAL"CHIP"
WATTAGE"1/20W"
CDS_LIB"pure_quanta"
PART_NUMBER"CS12001FE12";
"A"
$PN"1"20;
"B"
$PN"2"6;
%"Q_RES"
"2","(-1475,1300)","0","pure_quanta","I145";
;
LOCATION"R1454"
$SEC"1"
CDS_SEC"1"
MATERIAL"EMPTY"
VALUE"4.7K"
TOLERANCE"5%"
WATTAGE"1/20W"
PACK_TYPE"0201LF"
CDS_LIB"pure_quanta"
PART_NUMBER"CS24701JE04";
"A"
$PN"1"25;
"B"
$PN"2"21;
%"Q_RES"
"2","(-1200,1300)","0","pure_quanta","I146";
;
LOCATION"R1455"
$SEC"1"
CDS_SEC"1"
PACK_TYPE"0201LF"
MATERIAL"EMPTY"
VALUE"4.7K"
TOLERANCE"5%"
WATTAGE"1/20W"
CDS_LIB"pure_quanta"
PART_NUMBER"CS24701JE04";
"A"
$PN"1"25;
"B"
$PN"2"22;
%"GND"
"1","(-650,375)","0","pure_quanta_power","I148";
;
CDS_LIB"pure_quanta_power"
BOM_COST"MEM"
SIZE"1B"
HDL_POWER"GND";
"A<SIZE-1..0>\NAC"5;
%"Q_RES"
"2","(-650,675)","0","pure_quanta","I150";
;
LOCATION"R1373"
$SEC"1"
CDS_SEC"1"
MATERIAL"CHIP"
PACK_TYPE"0201LF"
VALUE"4.7K"
TOLERANCE"5%"
WATTAGE"1/20W"
CDS_LIB"pure_quanta"
PART_NUMBER"CS24701JE04";
"A"
$PN"1"24;
"B"
$PN"2"5;
%"Q_RES"
"2","(-650,1325)","0","pure_quanta","I151";
;
LOCATION"R1461"
$SEC"1"
CDS_SEC"1"
PACK_TYPE"0201LF"
MATERIAL"EMPTY"
WATTAGE"1/20W"
TOLERANCE"5%"
VALUE"4.7K"
CDS_LIB"pure_quanta"
PART_NUMBER"CS24701JE04";
"A"
$PN"1"25;
"B"
$PN"2"24;
%"P1V0"
"1","(-650,1625)","0","pure_quanta_power","I152";
;
HDL_POWER"P1V8_CPU1_RT_1D"
CDS_LIB"pure_quanta_power";
"A"25;
%"Q_RES"
"2","(-925,1300)","0","pure_quanta","I153";
;
LOCATION"R1456"
$SEC"1"
CDS_SEC"1"
PACK_TYPE"0201LF"
MATERIAL"EMPTY"
WATTAGE"1/20W"
VALUE"1K"
TOLERANCE"1%"
CDS_LIB"pure_quanta"
PART_NUMBER"CS21001FE07";
"A"
$PN"1"25;
"B"
$PN"2"23;
%"UNIVERSAL_GND"
"1","(-8825,3025)","0","pure_quanta_power","I17";
;
CDS_LIB"pure_quanta_power"
HDL_POWER"GND";
"A"6;
%"Q_RES"
"2","(-8825,3975)","0","pure_quanta","I19";
;
LOCATION"R755"
$SEC"1"
CDS_SEC"1"
VALUE"4.7K"
WATTAGE"1/20W"
MATERIAL"EMPTY"
PACK_TYPE"0201LF"
TOLERANCE"5%"
CDS_LIB"pure_quanta"
PART_NUMBER"CS24701JE04";
"A"
$PN"1"7;
"B"
$PN"2"20;
%"P1V0"
"1","(-8825,4300)","0","pure_quanta_power","I20";
;
HDL_POWER"P1V8_CPU1_RT_1D"
CDS_LIB"pure_quanta_power";
"A"7;
%"Q_RES"
"2","(-8800,4900)","0","pure_quanta","I21";
;
LOCATION"R782"
$SEC"1"
CDS_SEC"1"
PACK_TYPE"0201LF"
MATERIAL"CHIP"
WATTAGE"1/20W"
TOLERANCE"1%"
VALUE"10K"
CDS_LIB"pure_quanta"
PART_NUMBER"CS31001FE17";
"A"
$PN"1"40;
"B"
$PN"2"59;
%"Q_RES"
"2","(-8500,4900)","0","pure_quanta","I22";
;
LOCATION"R783"
$SEC"1"
CDS_SEC"1"
PACK_TYPE"0201LF"
MATERIAL"CHIP"
WATTAGE"1/20W"
TOLERANCE"1%"
VALUE"10K"
CDS_LIB"pure_quanta"
PART_NUMBER"CS31001FE17";
"A"
$PN"1"41;
"B"
$PN"2"59;
%"Q_RES"
"2","(-8175,4900)","0","pure_quanta","I23";
;
LOCATION"R785"
$SEC"1"
CDS_SEC"1"
MATERIAL"CHIP"
PACK_TYPE"0201LF"
WATTAGE"1/20W"
TOLERANCE"5%"
VALUE"4.7K"
CDS_LIB"pure_quanta"
PART_NUMBER"CS24701JE04";
"A"
$PN"1"42;
"B"
$PN"2"59;
%"Q_RES"
"2","(-8800,5850)","0","pure_quanta","I24";
;
LOCATION"R781"
$SEC"1"
CDS_SEC"1"
MATERIAL"EMPTY"
PACK_TYPE"0201LF"
WATTAGE"1/20W"
VALUE"4.7K"
TOLERANCE"5%"
CDS_LIB"pure_quanta"
PART_NUMBER"CS24701JE04";
"A"
$PN"1"58;
"B"
$PN"2"40;
%"Q_RES"
"2","(-8175,5850)","0","pure_quanta","I25";
;
LOCATION"R784"
$SEC"1"
CDS_SEC"1"
VALUE"4.7K"
WATTAGE"1/20W"
MATERIAL"EMPTY"
PACK_TYPE"0201LF"
TOLERANCE"5%"
CDS_LIB"pure_quanta"
PART_NUMBER"CS24701JE04";
"A"
$PN"1"58;
"B"
$PN"2"42;
%"P1V0"
"1","(-8800,6250)","0","pure_quanta_power","I26";
;
HDL_POWER"P1V8_CPU1_RT_1D"
CDS_LIB"pure_quanta_power";
"A"58;
%"UNIVERSAL_GND"
"1","(-6150,250)","0","pure_quanta_power","I29";
;
CDS_LIB"pure_quanta_power"
HDL_POWER"GND";
"A"8;
%"UNIVERSAL_GND"
"1","(-6000,250)","0","pure_quanta_power","I30";
;
CDS_LIB"pure_quanta_power"
HDL_POWER"GND";
"A"9;
%"Q_RES"
"2","(-6150,575)","2","pure_quanta","I31";
;
LOCATION"R625"
$SEC"1"
CDS_SEC"1"
MATERIAL"EMPTY"
PACK_TYPE"0201LF"
WATTAGE"1/20W"
TOLERANCE"1%"
VALUE"51.1"
CDS_LIB"pure_quanta"
PART_NUMBER"CS05111FE00";
"A"
$PN"1"45;
"B"
$PN"2"8;
%"Q_RES"
"2","(-6000,575)","0","pure_quanta","I32";
;
LOCATION"R626"
$SEC"1"
CDS_SEC"1"
PACK_TYPE"0201LF"
MATERIAL"EMPTY"
WATTAGE"1/20W"
VALUE"51.1"
TOLERANCE"1%"
CDS_LIB"pure_quanta"
PART_NUMBER"CS05111FE00";
"A"
$PN"1"48;
"B"
$PN"2"9;
%"Q_RES"
"1","(-6450,1050)","0","pure_quanta","I33";
;
LOCATION"R597"
SEC"1"
PACK_TYPE"0201LF"
MATERIAL"CHIP"
WATTAGE"1/20W"
VALUE"0"
TOLERANCE"5%"
SEC_TYPE"0201LF"
CDS_LIB"pure_quanta"
PART_NUMBER"CS00001JE10";
"B"
$PN"2"48;
"A"
$PN"1"47;
%"Q_RES"
"1","(-6450,900)","0","pure_quanta","I34";
;
LOCATION"R598"
SEC"1"
PACK_TYPE"0201LF"
MATERIAL"CHIP"
SEC_TYPE"0201LF"
WATTAGE"1/20W"
VALUE"0"
TOLERANCE"5%"
CDS_LIB"pure_quanta"
PART_NUMBER"CS00001JE10";
"B"
$PN"2"45;
"A"
$PN"1"46;
%"Q_RES"
"1","(-6175,1400)","0","pure_quanta","I35";
;
LOCATION"R671"
$SEC"1"
CDS_SEC"1"
PACK_TYPE"0201LF"
WATTAGE"1/20W"
MATERIAL"CHIP"
CDS_LIB"pure_quanta"
VALUE"49.9"
TOLERANCE"1%"
PART_NUMBER"CS04991FE06";
"B"
$PN"2"19;
"A"
$PN"1"18;
%"Q_RES"
"1","(-6175,1500)","0","pure_quanta","I36";
;
LOCATION"R670"
$SEC"1"
CDS_SEC"1"
WATTAGE"1/20W"
PACK_TYPE"0201LF"
MATERIAL"CHIP"
VALUE"49.9"
TOLERANCE"1%"
CDS_LIB"pure_quanta"
PART_NUMBER"CS04991FE06";
"B"
$PN"2"17;
"A"
$PN"1"16;
%"Q_RES"
"1","(-6200,2650)","0","pure_quanta","I43";
;
LOCATION"R780"
$SEC"1"
CDS_SEC"1"
WATTAGE"1/20W"
VALUE"0"
TOLERANCE"5%"
MATERIAL"CHIP"
PACK_TYPE"0201LF"
CDS_LIB"pure_quanta"
PART_NUMBER"CS00001JE10";
"B"
$PN"2"35;
"A"
$PN"1"51;
%"Q_RES"
"1","(-6200,2750)","0","pure_quanta","I44";
;
LOCATION"R779"
$SEC"1"
CDS_SEC"1"
PACK_TYPE"0201LF"
VALUE"0"
MATERIAL"CHIP"
TOLERANCE"5%"
WATTAGE"1/20W"
CDS_LIB"pure_quanta"
PART_NUMBER"CS00001JE10";
"B"
$PN"2"55;
"A"
$PN"1"52;
%"PT5161LRS"
"3","(-4225,2200)","0","pure_quanta","I47";
;
LOCATION"U6015"
$SEC"3"
CDS_SEC"3"
PART_TYPE"SMLF"
VALUE"PT5161LRS"
MATERIAL"IC"
CDS_LIB"pure_quanta"
CDS_LMAN_SYM_OUTLINE"-500,1450,450,-1400"
NEEDS_NO_SIZE"TRUE"
PART_NUMBER"AJ051610U03";
"EE_DAT"
$PN"FJ3"19;
"EE_CLK"
$PN"FF5"17;
"CLKREQ_N \B"
$PN"G35"72;
"TEST2"
$PN"FF30"32;
"TEST1"
$PN"FF27"33;
"TEST0"
$PN"FF24"34;
"T_SENSE"
$PN"E30"12;
"SMBDAT"
$PN"B28"35;
"SMBCLK"
$PN"B31"55;
"SMB_ADDR3"
$PN"B25"31;
"SMB_ADDR2"
$PN"B23"49;
"SMB_ADDR1"
$PN"F34"50;
"SCAN_MODE"
$PN"FF33"69;
"RXDET_BYP"
$PN"E11"68;
"RESET_N \B"
$PN"FF11"63;
"REFCLKP"
$PN"FJ16"48;
"REFCLKN"
$PN"FF18"45;
"REFCLK_OUTP"
$PN"B16"0;
"REFCLK_OUTN"
$PN"E18"0;
"PERST_N \B"
$PN"F2"71;
"MODE"
$PN"FJ9"67;
"JTAG_TRST_N \B"
$PN"E8"65;
"JTAG_TMS"
$PN"B12"26;
"JTAG_TEST_MODE"
$PN"FF8"66;
"JTAG_TDO"
$PN"B9"62;
"JTAG_TDI"
$PN"B6"64;
"JTAG_TCK"
$PN"B3"61;
"INT_N \B"
$PN"FJ31"0;
"GPIO3"
$PN"FJ28"43;
"GPIO2"
$PN"FJ25"53;
"GPIO1"
$PN"FJ23"0;
"GPIO0"
$PN"FJ6"0;
%"Q_RES"
"2","(-7875,4875)","0","pure_quanta","I51";
;
LOCATION"R787"
$SEC"1"
CDS_SEC"1"
MATERIAL"CHIP"
PACK_TYPE"0201LF"
VALUE"4.7K"
WATTAGE"1/20W"
TOLERANCE"5%"
CDS_LIB"pure_quanta"
PART_NUMBER"CS24701JE04";
"A"
$PN"1"44;
"B"
$PN"2"59;
%"Q_RES"
"2","(-7575,4875)","0","pure_quanta","I52";
;
LOCATION"R791"
$SEC"1"
CDS_SEC"1"
MATERIAL"CHIP"
WATTAGE"1/20W"
VALUE"4.7K"
TOLERANCE"5%"
PACK_TYPE"0201LF"
CDS_LIB"pure_quanta"
PART_NUMBER"CS24701JE04";
"A"
$PN"1"39;
"B"
$PN"2"59;
%"UNIVERSAL_GND"
"1","(-7275,4400)","0","pure_quanta_power","I53";
;
CDS_LIB"pure_quanta_power"
HDL_POWER"GND";
"A"59;
%"Q_RES"
"2","(-7275,4850)","0","pure_quanta","I54";
;
LOCATION"R792"
$SEC"1"
CDS_SEC"1"
TOLERANCE"5%"
VALUE"4.7K"
PACK_TYPE"0201LF"
MATERIAL"CHIP"
WATTAGE"1/20W"
CDS_LIB"pure_quanta"
PART_NUMBER"CS24701JE04";
"A"
$PN"1"38;
"B"
$PN"2"59;
%"Q_RES"
"2","(-7875,5800)","0","pure_quanta","I55";
;
LOCATION"R786"
$SEC"1"
CDS_SEC"1"
MATERIAL"EMPTY"
PACK_TYPE"0201LF"
VALUE"4.7K"
TOLERANCE"5%"
WATTAGE"1/20W"
CDS_LIB"pure_quanta"
PART_NUMBER"CS24701JE04";
"A"
$PN"1"58;
"B"
$PN"2"44;
%"Q_RES"
"2","(-7575,5825)","0","pure_quanta","I56";
;
LOCATION"R788"
$SEC"1"
CDS_SEC"1"
WATTAGE"1/20W"
PACK_TYPE"0201LF"
MATERIAL"EMPTY"
TOLERANCE"5%"
VALUE"4.7K"
CDS_LIB"pure_quanta"
PART_NUMBER"CS24701JE04";
"A"
$PN"1"58;
"B"
$PN"2"39;
%"Q_RES"
"2","(-7275,5850)","0","pure_quanta","I57";
;
LOCATION"R759"
$SEC"1"
CDS_SEC"1"
WATTAGE"1/20W"
VALUE"4.7K"
TOLERANCE"5%"
PACK_TYPE"0201LF"
MATERIAL"EMPTY"
CDS_LIB"pure_quanta"
PART_NUMBER"CS24701JE04";
"A"
$PN"1"58;
"B"
$PN"2"38;
%"UNIVERSAL_GND"
"1","(-4875,5050)","0","pure_quanta_power","I64";
;
CDS_LIB"pure_quanta_power"
HDL_POWER"GND";
"A"10;
%"Q_RES"
"2","(-4875,5400)","0","pure_quanta","I65";
;
LOCATION"R794"
$SEC"1"
CDS_SEC"1"
WATTAGE"1/20W"
PACK_TYPE"0201LF"
VALUE"4.7K"
TOLERANCE"5%"
MATERIAL"EMPTY"
CDS_LIB"pure_quanta"
PART_NUMBER"CS24701JE04";
"A"
$PN"1"37;
"B"
$PN"2"10;
%"Q_RES"
"2","(-4875,5925)","0","pure_quanta","I66";
;
LOCATION"R793"
$SEC"1"
CDS_SEC"1"
PACK_TYPE"0201LF"
MATERIAL"CHIP"
WATTAGE"1/20W"
TOLERANCE"5%"
VALUE"4.7K"
CDS_LIB"pure_quanta"
PART_NUMBER"CS24701JE04";
"A"
$PN"1"11;
"B"
$PN"2"37;
%"P1V0"
"1","(-4875,6250)","0","pure_quanta_power","I68";
;
HDL_POWER"P1V8_CPU1_RT_1D"
CDS_LIB"pure_quanta_power";
"A"11;
%"UNIVERSAL_GND"
"1","(-3150,1550)","1","pure_quanta_power","I69";
;
CDS_LIB"pure_quanta_power"
HDL_POWER"GND";
"A"12;
%"Q_RES"
"1","(-2425,2050)","0","pure_quanta","I70";
;
LOCATION"R731"
SEC"1"
VALUE"0"
PACK_TYPE"0201LF"
CDS_LIB"pure_quanta"
SEC_TYPE"0201LF"
MATERIAL"CHIP"
TOLERANCE"5%"
WATTAGE"1/20W"
PART_NUMBER"CS00001JE10";
"B"
$PN"2"60;
"A"
$PN"1"71;
%"Q_RES"
"1","(-2425,1950)","0","pure_quanta","I71";
;
LOCATION"R732"
$SEC"1"
CDS_SEC"1"
PACK_TYPE"0201LF"
VALUE"0"
WATTAGE"1/20W"
TOLERANCE"5%"
MATERIAL"CHIP"
CDS_LIB"pure_quanta"
PART_NUMBER"CS00001JE10";
"B"
$PN"2"70;
"A"
$PN"1"63;
%"GND"
"1","(-1325,4700)","0","pure_quanta_power","I87";
;
BOM_COST"MEM"
SIZE"1B"
CDS_LIB"pure_quanta_power"
HDL_POWER"GND";
"A<SIZE-1..0>\NAC"13;
%"GND"
"1","(-1150,4725)","0","pure_quanta_power","I88";
;
CDS_LIB"pure_quanta_power"
BOM_COST"MEM"
SIZE"1B"
HDL_POWER"GND";
"A<SIZE-1..0>\NAC"14;
%"Q_RES"
"2","(-1325,5075)","2","pure_quanta","I92";
;
LOCATION"R752"
$SEC"1"
CDS_SEC"1"
TOLERANCE"1%"
MATERIAL"CHIP"
WATTAGE"1/20W"
PACK_TYPE"0201LF"
VALUE"10K"
CDS_LIB"pure_quanta"
PART_NUMBER"CS31001FE17";
"A"
$PN"1"27;
"B"
$PN"2"13;
%"Q_RES"
"2","(-1150,5075)","0","pure_quanta","I93";
;
LOCATION"R749"
$SEC"1"
CDS_SEC"1"
PACK_TYPE"0201LF"
MATERIAL"CHIP"
WATTAGE"1/20W"
VALUE"10K"
TOLERANCE"1%"
CDS_LIB"pure_quanta"
PART_NUMBER"CS31001FE17";
"A"
$PN"1"36;
"B"
$PN"2"14;
%"Q_RES"
"2","(-1325,5900)","2","pure_quanta","I94";
;
LOCATION"R758"
$SEC"1"
CDS_SEC"1"
MATERIAL"EMPTY"
TOLERANCE"5%"
VALUE"4.7K"
WATTAGE"1/20W"
PACK_TYPE"0201LF"
CDS_LIB"pure_quanta"
PART_NUMBER"CS24701JE04";
"A"
$PN"1"15;
"B"
$PN"2"27;
%"P1V0"
"1","(-1325,6150)","0","pure_quanta_power","I97";
;
HDL_POWER"P1V8_CPU1_RT_1D"
CDS_LIB"pure_quanta_power";
"A"15;
END.
